# S9S_MB_2U (Grand Teton) — schematic netlist excerpt (pin names and nets, part order shuffled) for the footprints in the layout excerpt that follows; sources: Cadence DE-HDL packaged netlist, KiCad conversion of 03242023_DA0F0TMBIJ0_F0T_Motherboard_J_brd_V01_OCP.brd

PPQ6  MOSFET_NCH_1D3S  PSMNR58-30YLH EMPTY  pkg SOT1023  page 304
  \1\  = P12V_AUX
  \2\  = P12V_AUX
  \3\  = P12V_AUX
  \4\  = P12V_HSC_GATE_G2
  \5\  = P12V_MAIN_R

R2113  Q_RES  33.2 1% CHIP  pkg 0402LF  page 190 : A = RST_PCIE_PCH_DEV_BUF_M2_0_PERST ; B = RST_PCIE_PCH_DEV_0_N

(kicad_pcb
	(version 20260206)
	(generator "pcbnew")
	(generator_version "10.0")
	(general
		(thickness 1.6)
		(legacy_teardrops no)
	)
	(paper "A4")
	(title_block
		(title "03242023_DA0F0TMBIJ0_F0T_Motherboard_J_brd_V01_OCP.brd")
		(comment 1 "Grand Teton / footprints 235-236 of 6105")
	)
	(layers
		(0 "F.Cu" signal "TOP")
		(4 "In1.Cu" signal "GND")
		(6 "In2.Cu" signal "IN1")
		(8 "In3.Cu" signal "GND1")
		(10 "In4.Cu" signal "IN2")
		(12 "In5.Cu" signal "GND2")
		(14 "In6.Cu" signal "IN3")
		(16 "In7.Cu" signal "GND3")
		(18 "In8.Cu" signal "VCC")
		(20 "In9.Cu" signal "VCC1")
		(22 "In10.Cu" signal "GND4")
		(24 "In11.Cu" signal "IN4")
		(26 "In12.Cu" signal "GND5")
		(28 "In13.Cu" signal "IN5")
		(30 "In14.Cu" signal "GND6")
		(32 "In15.Cu" signal "IN6")
		(34 "In16.Cu" signal "GND7")
		(2 "B.Cu" signal "BOTTOM")
		(9 "F.Adhes" user "F.Adhesive")
		(11 "B.Adhes" user "B.Adhesive")
		(13 "F.Paste" user "Package Geometry/Pastemask Top")
		(15 "B.Paste" user "Package Geometry/Pastemask Bottom")
		(5 "F.SilkS" user "Ref Des/Silkscreen Top")
		(7 "B.SilkS" user "Ref Des/Silkscreen Bottom")
		(1 "F.Mask" user "Board Geometry/Soldermask Top")
		(3 "B.Mask" user "Board Geometry/Soldermask Bottom")
		(17 "Dwgs.User" user "User.Drawings")
		(19 "Cmts.User" user "User.Comments")
		(21 "Eco1.User" user "User.Eco1")
		(23 "Eco2.User" user "User.Eco2")
		(25 "Edge.Cuts" user "Board Geometry/Outline")
		(27 "Margin" user)
		(31 "F.CrtYd" user "Package Geometry/Place Bound Top")
		(29 "B.CrtYd" user "Package Geometry/Place Bound Bottom")
		(35 "F.Fab" user "Ref Des/Assembly Top")
		(33 "B.Fab" user "Ref Des/Assembly Bottom")
	)
	(footprint ""
		(layer "F.Cu")
		(at 142.42288 -40.985948)
		(property "Reference" "R2113"
			(at 0 0 0)
			(layer "F.SilkS")
			(hide yes)
			(effects
				(font
					(size 1.27 1.27)
				)
			)
		)
		(property "Value" ""
			(at 0 0 0)
			(layer "F.Fab")
			(effects
				(font
					(size 1.27 1.27)
				)
			)
		)
		(duplicate_pad_numbers_are_jumpers no)
		(fp_line
			(start -0.7874 -0.4064)
			(end 0.7874 -0.4064)
			(stroke
				(width 0.1524)
				(type default)
			)
			(layer "F.SilkS")
		)
		(fp_line
			(start -0.7874 0.4064)
			(end -0.7874 -0.4064)
			(stroke
				(width 0.1524)
				(type default)
			)
			(layer "F.SilkS")
		)
		(fp_line
			(start 0.7874 -0.4064)
			(end 0.7874 0.4064)
			(stroke
				(width 0.1524)
				(type default)
			)
			(layer "F.SilkS")
		)
		(fp_line
			(start 0.7874 0.4064)
			(end -0.7874 0.4064)
			(stroke
				(width 0.1524)
				(type default)
			)
			(layer "F.SilkS")
		)
		(fp_line
			(start -0.67945 -0.305054)
			(end -0.12065 -0.305054)
			(stroke
				(width 0.1)
				(type default)
			)
			(layer "F.Fab")
		)
		(fp_line
			(start -0.67945 0.3048)
			(end -0.67945 -0.305054)
			(stroke
				(width 0.1)
				(type default)
			)
			(layer "F.Fab")
		)
		(fp_line
			(start -0.12065 -0.305054)
			(end -0.12065 -0.2794)
			(stroke
				(width 0.1)
				(type default)
			)
			(layer "F.Fab")
		)
		(fp_line
			(start -0.12065 -0.2794)
			(end 0.12065 -0.2794)
			(stroke
				(width 0.1)
				(type default)
			)
			(layer "F.Fab")
		)
		(fp_line
			(start -0.12065 0.2794)
			(end -0.12065 0.3048)
			(stroke
				(width 0.1)
				(type default)
			)
			(layer "F.Fab")
		)
		(fp_line
			(start -0.12065 0.3048)
			(end -0.67945 0.3048)
			(stroke
				(width 0.1)
				(type default)
			)
			(layer "F.Fab")
		)
		(fp_line
			(start 0.120396 0.2794)
			(end -0.12065 0.2794)
			(stroke
				(width 0.1)
				(type default)
			)
			(layer "F.Fab")
		)
		(fp_line
			(start 0.120396 0.3048)
			(end 0.120396 0.2794)
			(stroke
				(width 0.1)
				(type default)
			)
			(layer "F.Fab")
		)
		(fp_line
			(start 0.12065 -0.3048)
			(end 0.67945 -0.3048)
			(stroke
				(width 0.1)
				(type default)
			)
			(layer "F.Fab")
		)
		(fp_line
			(start 0.12065 -0.2794)
			(end 0.12065 -0.3048)
			(stroke
				(width 0.1)
				(type default)
			)
			(layer "F.Fab")
		)
		(fp_line
			(start 0.67945 -0.3048)
			(end 0.67945 0.3048)
			(stroke
				(width 0.1)
				(type default)
			)
			(layer "F.Fab")
		)
		(fp_line
			(start 0.67945 0.3048)
			(end 0.120396 0.3048)
			(stroke
				(width 0.1)
				(type default)
			)
			(layer "F.Fab")
		)
		(pad "1" smd circle
			(at -0.40005 0)
			(size 0 0)
			(layers "F.Cu" "F.Mask" "F.Paste")
			(net "RST_PCIE_PCH_DEV_BUF_M2_0_PERST")
		)
		(pad "2" smd circle
			(at 0.40005 0)
			(size 0 0)
			(layers "F.Cu" "F.Mask" "F.Paste")
			(net "RST_PCIE_PCH_DEV_0_N")
		)
	)
	(footprint ""
		(layer "F.Cu")
		(at 260.096508 -398.78 90)
		(property "Reference" "PPQ6"
			(at -8.10514 -1.938528 0)
			(unlocked yes)
			(layer "F.SilkS")
			(effects
				(font
					(size 0.7874 0.5842)
					(thickness 0.1524)
				)
				(justify left)
			)
		)
		(property "Value" ""
			(at 0 0 90)
			(layer "F.Fab")
			(effects
				(font
					(size 1.27 1.27)
				)
			)
		)
		(duplicate_pad_numbers_are_jumpers no)
		(fp_line
			(start 2.350008 -2.649982)
			(end 2.350008 -2.4892)
			(stroke
				(width 0.1524)
				(type default)
			)
			(layer "F.SilkS")
		)
		(fp_line
			(start -2.350008 -2.649982)
			(end 2.350008 -2.649982)
			(stroke
				(width 0.1524)
				(type default)
			)
			(layer "F.SilkS")
		)
		(fp_line
			(start -2.350008 -2.4384)
			(end -2.350008 -2.649982)
			(stroke
				(width 0.1524)
				(type default)
			)
			(layer "F.SilkS")
		)
		(fp_line
			(start 2.350008 2.4892)
			(end 2.350008 2.649982)
			(stroke
				(width 0.1524)
				(type default)
			)
			(layer "F.SilkS")
		)
		(fp_line
			(start 2.350008 2.649982)
			(end -2.350008 2.649982)
			(stroke
				(width 0.1524)
				(type default)
			)
			(layer "F.SilkS")
		)
		(fp_line
			(start -2.350008 2.649982)
			(end -2.350008 2.413)
			(stroke
				(width 0.1524)
				(type default)
			)
			(layer "F.SilkS")
		)
		(fp_poly
			(pts
				(xy -3.717544 -1.905) (xy -4.758944 -2.3241) (xy -4.758944 -1.524)
			)
			(stroke
				(width 0)
				(type default)
			)
			(fill yes)
			(layer "F.SilkS")
		)
		(fp_line
			(start 2.350008 -2.649982)
			(end 2.350008 2.649982)
			(stroke
				(width 0.1)
				(type default)
			)
			(layer "F.Fab")
		)
		(fp_line
			(start -2.350008 -2.649982)
			(end 2.350008 -2.649982)
			(stroke
				(width 0.1)
				(type default)
			)
			(layer "F.Fab")
		)
		(fp_line
			(start 2.350008 2.649982)
			(end -2.350008 2.649982)
			(stroke
				(width 0.1)
				(type default)
			)
			(layer "F.Fab")
		)
		(fp_line
			(start -2.350008 2.649982)
			(end -2.350008 -2.649982)
			(stroke
				(width 0.1)
				(type default)
			)
			(layer "F.Fab")
		)
		(fp_poly
			(pts
				(xy -3.717544 -1.905) (xy -4.758944 -2.3241) (xy -4.758944 -1.524)
			)
			(stroke
				(width 0)
				(type default)
			)
			(fill yes)
			(layer "F.Fab")
		)
		(pad "1" smd rect
			(at -2.999994 -1.905)
			(size 0.7112 1.1684)
			(layers "F.Cu" "F.Mask" "F.Paste")
			(net "P12V_AUX")
		)
		(pad "2" smd rect
			(at -2.999994 -0.635)
			(size 0.7112 1.1684)
			(layers "F.Cu" "F.Mask" "F.Paste")
			(net "P12V_AUX")
		)
		(pad "3" smd rect
			(at -2.999994 0.635)
			(size 0.7112 1.1684)
			(layers "F.Cu" "F.Mask" "F.Paste")
			(net "P12V_AUX")
		)
		(pad "4" smd rect
			(at -2.999994 1.905)
			(size 0.7112 1.1684)
			(layers "F.Cu" "F.Mask" "F.Paste")
			(net "P12V_HSC_GATE_G2")
		)
		(pad "5" smd circle
			(at 0.925068 0)
			(size 0 0)
			(layers "F.Cu" "F.Mask" "F.Paste")
			(net "P12V_MAIN_R")
		)
		(zone
			(layer "F.Cu")
			(hatch none 0.5)
			(connect_pads
				(clearance 0)
			)
			(min_thickness 0.25)
			(keepout
				(tracks not_allowed)
				(vias allowed)
				(pads allowed)
				(copperpour not_allowed)
				(footprints allowed)
			)
			(placement
				(enabled no)
				(sheetname "")
			)
			(fill
				(thermal_gap 0.5)
				(thermal_bridge_width 0.5)
				(island_removal_mode 0)
			)
			(polygon
				(pts
					(xy 257.937508 -397.3322) (xy 262.255508 -397.3322) (xy 262.738108 -397.3322) (xy 262.738108 -396.4305)
					(xy 257.454908 -396.4305) (xy 257.454908 -397.3322)
				)
			)
		)
	)
)
